(kicad_pcb
	(version 20241229)
	(generator "pcbnew")
	(generator_version "9.0")
	(general
		(thickness 1.6296)
		(legacy_teardrops no)
	)
	(paper "A3")
	(title_block
		(title "Thunderbolt to 10GbE adapter")
		(date "2026-04-21")
		(rev "1.1.0")
		(company "Antmicro Ltd")
		(comment 1 "www.antmicro.com")
		(comment 9 "footprints 201-204 of 703")
	)
	(layers
		(0 "F.Cu" signal)
		(4 "In1.Cu" signal)
		(6 "In2.Cu" signal)
		(8 "In3.Cu" signal)
		(10 "In4.Cu" signal)
		(12 "In5.Cu" signal)
		(14 "In6.Cu" signal)
		(2 "B.Cu" signal)
		(9 "F.Adhes" user "F.Adhesive")
		(11 "B.Adhes" user "B.Adhesive")
		(13 "F.Paste" user)
		(15 "B.Paste" user)
		(5 "F.SilkS" user "F.Silkscreen")
		(7 "B.SilkS" user "B.Silkscreen")
		(1 "F.Mask" user)
		(3 "B.Mask" user)
		(17 "Dwgs.User" user "User.Drawings")
		(19 "Cmts.User" user "User.Comments")
		(21 "Eco1.User" user "User.Eco1")
		(23 "Eco2.User" user "User.Eco2")
		(25 "Edge.Cuts" user)
		(27 "Margin" user)
		(31 "F.CrtYd" user "F.Courtyard")
		(29 "B.CrtYd" user "B.Courtyard")
		(35 "F.Fab" user)
		(33 "B.Fab" user)
	)
	(footprint "antmicro-footprints:R_0402_1005Metric"
		(layer "F.Cu")
		(at 151.550002 108.15 180)
		(descr "Resistor SMD 0402")
		(tags "resistor SMD 0402")
		(property "Reference" "R89"
			(at -14.149998 -17.25 180)
			(layer "F.SilkS")
			(effects
				(font
					(size 0.7 0.7)
					(thickness 0.15)
				)
			)
		)
		(property "Value" "R_100k_0402"
			(at -1.011843 1.772047 180)
			(layer "F.Fab")
			(effects
				(font
					(size 0.7 0.7)
					(thickness 0.15)
				)
				(justify left bottom)
			)
		)
		(property "Datasheet" "https://www.bourns.com/docs/product-datasheets/cr.pdf"
			(at 0 0 180)
			(layer "F.Fab")
			(hide yes)
			(effects
				(font
					(size 1.27 1.27)
					(thickness 0.15)
				)
			)
		)
		(property "Description" "SMD Chip Resistor, 100 kohm, ± 1%, 62.5 mW, 0402 [1005 Metric], Thick Film, General Purpose"
			(at 0 0 180)
			(layer "F.Fab")
			(hide yes)
			(effects
				(font
					(size 1.27 1.27)
					(thickness 0.15)
				)
			)
		)
		(property "MPN" "CR0402-FX-1003GLF"
			(at 0 0 180)
			(unlocked yes)
			(layer "F.Fab")
			(hide yes)
			(effects
				(font
					(size 1 1)
					(thickness 0.15)
				)
			)
		)
		(property "Manufacturer" "Bourns"
			(at 0 0 180)
			(unlocked yes)
			(layer "F.Fab")
			(hide yes)
			(effects
				(font
					(size 1 1)
					(thickness 0.15)
				)
			)
		)
		(property "License" "Apache-2.0"
			(at 0 0 180)
			(unlocked yes)
			(layer "F.Fab")
			(hide yes)
			(effects
				(font
					(size 1 1)
					(thickness 0.15)
				)
			)
		)
		(property "Author" "Antmicro"
			(at 0 0 180)
			(unlocked yes)
			(layer "F.Fab")
			(hide yes)
			(effects
				(font
					(size 1 1)
					(thickness 0.15)
				)
			)
		)
		(property "Val" "100k"
			(at 0 0 180)
			(unlocked yes)
			(layer "F.Fab")
			(hide yes)
			(effects
				(font
					(size 1 1)
					(thickness 0.15)
				)
			)
		)
		(property "Tolerance" "1%"
			(at 0 0 180)
			(unlocked yes)
			(layer "F.Fab")
			(hide yes)
			(effects
				(font
					(size 1 1)
					(thickness 0.15)
				)
			)
		)
		(sheetname "/X710 DCDC converters/")
		(sheetfile "DCDC_converters_X710.kicad_sch")
		(attr smd)
		(fp_rect
			(start -0.925 -0.47)
			(end 0.925 0.47)
			(stroke
				(width 0.05)
				(type default)
			)
			(fill no)
			(layer "F.CrtYd")
		)
		(fp_rect
			(start -0.5 -0.25)
			(end 0.5 0.25)
			(stroke
				(width 0.15)
				(type solid)
			)
			(fill no)
			(layer "F.Fab")
		)
		(fp_text user "License: Apache-2.0"
			(at -0.95 5.169 180)
			(layer "F.Fab")
			(effects
				(font
					(size 0.7 0.7)
					(thickness 0.15)
				)
				(justify left bottom)
			)
		)
		(fp_text user "Author: Antmicro"
			(at -0.95 4.169 180)
			(layer "F.Fab")
			(effects
				(font
					(size 0.7 0.7)
					(thickness 0.15)
				)
				(justify left bottom)
			)
		)
		(fp_text user "${REFERENCE}"
			(at -0.95 3.168 180)
			(layer "F.Fab")
			(effects
				(font
					(size 0.7 0.7)
					(thickness 0.15)
				)
				(justify left bottom)
			)
		)
		(pad "1" smd roundrect
			(at -0.48 0 180)
			(size 0.59 0.64)
			(layers "F.Cu" "F.Mask" "F.Paste")
			(roundrect_rratio 0.25)
			(net 380 "/X710 DCDC converters/1V88_PG")
			(pintype "passive")
		)
		(pad "2" smd roundrect
			(at 0.48 0 180)
			(size 0.59 0.64)
			(layers "F.Cu" "F.Mask" "F.Paste")
			(roundrect_rratio 0.25)
			(net 108 "/X710 DCDC converters/1V88_VCC")
			(pintype "passive")
		)
	)
	(footprint "antmicro-footprints:LED_0603_1608Metric_G"
		(layer "F.Cu")
		(at 183.2 73)
		(descr "LED SMD 0603 Green")
		(tags "LED SMD 0603 Green")
		(property "Reference" "D8"
			(at -1.2 6.75 0)
			(layer "F.SilkS")
			(effects
				(font
					(size 0.7 0.7)
					(thickness 0.15)
				)
				(justify left bottom)
			)
		)
		(property "Value" "LED_G_0603_LG_L29K-G2J1-24-Z"
			(at -0.001 1.599 0)
			(layer "F.Fab")
			(effects
				(font
					(size 0.7 0.7)
					(thickness 0.15)
				)
				(justify left bottom)
			)
		)
		(property "Datasheet" "https://look.ams-osram.com/m/19ee86b3ae0ee95b/original/LG-L29K.pdf"
			(at 0 0 0)
			(layer "F.Fab")
			(hide yes)
			(effects
				(font
					(size 1.27 1.27)
					(thickness 0.15)
				)
			)
		)
		(property "Description" "LED, Green, SMD, 0603, 20 mA, 1.7 V, 570 nm"
			(at 0 0 0)
			(layer "F.Fab")
			(hide yes)
			(effects
				(font
					(size 1.27 1.27)
					(thickness 0.15)
				)
			)
		)
		(property "MPN" "LG L29K-G2J1-24-Z"
			(at 0 0 0)
			(unlocked yes)
			(layer "F.Fab")
			(hide yes)
			(effects
				(font
					(size 1 1)
					(thickness 0.15)
				)
			)
		)
		(property "Manufacturer" "OSRAM"
			(at 0 0 0)
			(unlocked yes)
			(layer "F.Fab")
			(hide yes)
			(effects
				(font
					(size 1 1)
					(thickness 0.15)
				)
			)
		)
		(property "Color" "Green"
			(at 0 0 0)
			(unlocked yes)
			(layer "F.Fab")
			(hide yes)
			(effects
				(font
					(size 1 1)
					(thickness 0.15)
				)
			)
		)
		(property "Author" "Antmicro"
			(at 0 0 0)
			(unlocked yes)
			(layer "F.Fab")
			(hide yes)
			(effects
				(font
					(size 1 1)
					(thickness 0.15)
				)
			)
		)
		(property "License" "Apache-2.0"
			(at 0 0 0)
			(unlocked yes)
			(layer "F.Fab")
			(hide yes)
			(effects
				(font
					(size 1 1)
					(thickness 0.15)
				)
			)
		)
		(sheetname "/X710 DCDC converters/")
		(sheetfile "DCDC_converters_X710.kicad_sch")
		(attr smd)
		(fp_line
			(start -1.18 -0.319)
			(end -1.18 0.321)
			(stroke
				(width 0.15)
				(type solid)
			)
			(layer "F.SilkS")
		)
		(fp_line
			(start -0.094672 0.001008)
			(end -0.24 0.001008)
			(stroke
				(width 0.1)
				(type solid)
			)
			(layer "F.SilkS")
		)
		(fp_line
			(start -0.094672 0.001008)
			(end 0.105328 -0.198992)
			(stroke
				(width 0.1)
				(type solid)
			)
			(layer "F.SilkS")
		)
		(fp_line
			(start -0.094672 0.201008)
			(end -0.094672 -0.198992)
			(stroke
				(width 0.1)
				(type solid)
			)
			(layer "F.SilkS")
		)
		(fp_line
			(start 0.105328 0.001008)
			(end 0.24 0.001)
			(stroke
				(width 0.1)
				(type solid)
			)
			(layer "F.SilkS")
		)
		(fp_line
			(start 0.105328 0.201008)
			(end -0.094672 0.001008)
			(stroke
				(width 0.1)
				(type solid)
			)
			(layer "F.SilkS")
		)
		(fp_line
			(start 0.105328 0.201008)
			(end 0.105328 -0.198992)
			(stroke
				(width 0.1)
				(type solid)
			)
			(layer "F.SilkS")
		)
		(fp_line
			(start 0.22 -0.35)
			(end -0.22 -0.35)
			(stroke
				(width 0.15)
				(type solid)
			)
			(layer "F.SilkS")
		)
		(fp_line
			(start 0.22 0.35)
			(end -0.22 0.35)
			(stroke
				(width 0.15)
				(type solid)
			)
			(layer "F.SilkS")
		)
		(fp_rect
			(start 1.25 0.65)
			(end -1.25 -0.65)
			(stroke
				(width 0.05)
				(type solid)
			)
			(fill no)
			(layer "F.CrtYd")
		)
		(fp_line
			(start -0.199 -0.202)
			(end -0.199 0.1)
			(stroke
				(width 0.15)
				(type solid)
			)
			(layer "F.Fab")
		)
		(fp_line
			(start -0.199 0)
			(end -0.597 0)
			(stroke
				(width 0.15)
				(type solid)
			)
			(layer "F.Fab")
		)
		(fp_line
			(start -0.199 0.2)
			(end -0.199 0.1)
			(stroke
				(width 0.15)
				(type solid)
			)
			(layer "F.Fab")
		)
		(fp_line
			(start -0.101 0)
			(end 0.201 0.2)
			(stroke
				(width 0.15)
				(type solid)
			)
			(layer "F.Fab")
		)
		(fp_line
			(start 0.201 -0.202)
			(end -0.101 0)
			(stroke
				(width 0.15)
				(type solid)
			)
			(layer "F.Fab")
		)
		(fp_line
			(start 0.201 0)
			(end 0.201 -0.202)
			(stroke
				(width 0.15)
				(type solid)
			)
			(layer "F.Fab")
		)
		(fp_line
			(start 0.201 0.2)
			(end 0.201 0)
			(stroke
				(width 0.15)
				(type solid)
			)
			(layer "F.Fab")
		)
		(fp_line
			(start 0.599 0)
			(end 0.201 0)
			(stroke
				(width 0.15)
				(type solid)
			)
			(layer "F.Fab")
		)
		(fp_rect
			(start 0.848 0.4)
			(end -0.85 -0.402)
			(stroke
				(width 0.15)
				(type solid)
			)
			(fill no)
			(layer "F.Fab")
		)
		(fp_text user "${REFERENCE}"
			(at -1.4224 5.999 0)
			(layer "F.Fab")
			(effects
				(font
					(size 0.7 0.7)
					(thickness 0.15)
				)
				(justify left bottom)
			)
		)
		(fp_text user "License: Apache-2.0"
			(at -1.4224 3.599 0)
			(layer "F.Fab")
			(effects
				(font
					(size 0.7 0.7)
					(thickness 0.15)
				)
				(justify left bottom)
			)
		)
		(fp_text user "Author: Antmicro"
			(at -1.4224 4.799 0)
			(layer "F.Fab")
			(effects
				(font
					(size 0.7 0.7)
					(thickness 0.15)
				)
				(justify left bottom)
			)
		)
		(pad "1" smd roundrect
			(at -0.7 0 180)
			(size 0.8 1)
			(layers "F.Cu" "F.Mask" "F.Paste")
			(roundrect_rratio 0.2)
			(net 54 "Net-(D8-C)")
			(pinfunction "C")
			(pintype "passive")
		)
		(pad "2" smd roundrect
			(at 0.7 0 180)
			(size 0.8 1)
			(layers "F.Cu" "F.Mask" "F.Paste")
			(roundrect_rratio 0.2)
			(net 334 "/X710 DCDC converters/+3V3_OUT")
			(pinfunction "A")
			(pintype "passive")
		)
	)
	(footprint "antmicro-footprints:C_0603_1608Metric_EIA"
		(layer "F.Cu")
		(at 135.320002 92.600002)
		(descr "Capacitor SMD 0603, IPC-7351 Density Level A")
		(tags "Capacitor 0603")
		(property "Reference" "C134"
			(at 36.934999 -9.199999 0)
			(layer "F.SilkS")
			(effects
				(font
					(size 0.7 0.7)
					(thickness 0.15)
				)
			)
		)
		(property "Value" "C_22u_16V_0603"
			(at -1.42757 1.770288 0)
			(layer "F.Fab")
			(effects
				(font
					(size 0.7 0.7)
					(thickness 0.15)
				)
				(justify left bottom)
			)
		)
		(property "Datasheet" "https://product.samsungsem.com/mlcc/CL10A226MO7JZN.do"
			(at 0 0 0)
			(layer "F.Fab")
			(hide yes)
			(effects
				(font
					(size 1.27 1.27)
					(thickness 0.15)
				)
			)
		)
		(property "Description" "SMD Multilayer Ceramic Capacitor"
			(at 0 0 0)
			(layer "F.Fab")
			(hide yes)
			(effects
				(font
					(size 1.27 1.27)
					(thickness 0.15)
				)
			)
		)
		(property "MPN" "CL10A226MO7JZNC"
			(at 0 0 0)
			(unlocked yes)
			(layer "F.Fab")
			(hide yes)
			(effects
				(font
					(size 1 1)
					(thickness 0.15)
				)
			)
		)
		(property "Manufacturer" "Samsung Electro-Mechanics"
			(at 0 0 0)
			(unlocked yes)
			(layer "F.Fab")
			(hide yes)
			(effects
				(font
					(size 1 1)
					(thickness 0.15)
				)
			)
		)
		(property "License" "Apache-2.0"
			(at 0 0 0)
			(unlocked yes)
			(layer "F.Fab")
			(hide yes)
			(effects
				(font
					(size 1 1)
					(thickness 0.15)
				)
			)
		)
		(property "Author" "Antmicro"
			(at 0 0 0)
			(unlocked yes)
			(layer "F.Fab")
			(hide yes)
			(effects
				(font
					(size 1 1)
					(thickness 0.15)
				)
			)
		)
		(property "Val" "22u"
			(at 0 0 0)
			(unlocked yes)
			(layer "F.Fab")
			(hide yes)
			(effects
				(font
					(size 1 1)
					(thickness 0.15)
				)
			)
		)
		(property "Voltage" "16V"
			(at 0 0 0)
			(unlocked yes)
			(layer "F.Fab")
			(hide yes)
			(effects
				(font
					(size 1 1)
					(thickness 0.15)
				)
			)
		)
		(property "Dielectric" ""
			(at 0 0 0)
			(unlocked yes)
			(layer "F.Fab")
			(hide yes)
			(effects
				(font
					(size 1 1)
					(thickness 0.15)
				)
			)
		)
		(sheetname "/X710 DCDC converters/")
		(sheetfile "DCDC_converters_X710.kicad_sch")
		(attr smd)
		(fp_line
			(start -0.15 -0.55)
			(end 0.15 -0.55)
			(stroke
				(width 0.15)
				(type solid)
			)
			(layer "F.SilkS")
		)
		(fp_line
			(start -0.15 0.55)
			(end 0.15 0.55)
			(stroke
				(width 0.15)
				(type solid)
			)
			(layer "F.SilkS")
		)
		(fp_rect
			(start -1.25 -0.65)
			(end 1.25 0.65)
			(stroke
				(width 0.05)
				(type solid)
			)
			(fill no)
			(layer "F.CrtYd")
		)
		(fp_rect
			(start -0.8 -0.45)
			(end 0.8 0.45)
			(stroke
				(width 0.15)
				(type solid)
			)
			(fill no)
			(layer "F.Fab")
		)
		(fp_text user "License: Apache-2.0"
			(at -1.682 5.895 0)
			(layer "F.Fab")
			(effects
				(font
					(size 0.7 0.7)
					(thickness 0.15)
				)
				(justify left bottom)
			)
		)
		(fp_text user "${REFERENCE}"
			(at -1.682 3.895 0)
			(layer "F.Fab")
			(effects
				(font
					(size 0.7 0.7)
					(thickness 0.15)
				)
				(justify left bottom)
			)
		)
		(fp_text user "Author: Antmicro"
			(at -1.682 4.894 0)
			(layer "F.Fab")
			(effects
				(font
					(size 0.7 0.7)
					(thickness 0.15)
				)
				(justify left bottom)
			)
		)
		(pad "1" smd roundrect
			(at -0.7 0)
			(size 0.8 1.1)
			(layers "F.Cu" "F.Mask" "F.Paste")
			(roundrect_rratio 0.2)
			(net 23 "GND")
			(pintype "passive")
		)
		(pad "2" smd roundrect
			(at 0.7 0)
			(size 0.8 1.1)
			(layers "F.Cu" "F.Mask" "F.Paste")
			(roundrect_rratio 0.2)
			(net 334 "/X710 DCDC converters/+3V3_OUT")
			(pintype "passive")
		)
	)
	(footprint "antmicro-footprints:R_0402_1005Metric"
		(layer "F.Cu")
		(at 153.8 47.9 180)
		(descr "Resistor SMD 0402")
		(tags "resistor SMD 0402")
		(property "Reference" "R226"
			(at 1.8 -1.4 180)
			(layer "F.SilkS")
			(effects
				(font
					(size 0.7 0.7)
					(thickness 0.15)
				)
				(justify left bottom)
			)
		)
		(property "Value" "R_20k_0402"
			(at -1.011843 1.772047 180)
			(layer "F.Fab")
			(effects
				(font
					(size 0.7 0.7)
					(thickness 0.15)
				)
				(justify left bottom)
			)
		)
		(property "Datasheet" "https://www.bourns.com/docs/product-datasheets/cr.pdf"
			(at 0 0 180)
			(layer "F.Fab")
			(hide yes)
			(effects
				(font
					(size 1.27 1.27)
					(thickness 0.15)
				)
			)
		)
		(property "Description" "SMD Chip Resistor, 20 kohm, ± 1%, 62.5 mW, 0402 [1005 Metric], Thick Film, General Purpose"
			(at 0 0 180)
			(layer "F.Fab")
			(hide yes)
			(effects
				(font
					(size 1.27 1.27)
					(thickness 0.15)
				)
			)
		)
		(property "MPN" "CR0402-FX-2002GLF"
			(at 0 0 180)
			(unlocked yes)
			(layer "F.Fab")
			(hide yes)
			(effects
				(font
					(size 1 1)
					(thickness 0.15)
				)
			)
		)
		(property "Manufacturer" "Bourns"
			(at 0 0 180)
			(unlocked yes)
			(layer "F.Fab")
			(hide yes)
			(effects
				(font
					(size 1 1)
					(thickness 0.15)
				)
			)
		)
		(property "License" "Apache-2.0"
			(at 0 0 180)
			(unlocked yes)
			(layer "F.Fab")
			(hide yes)
			(effects
				(font
					(size 1 1)
					(thickness 0.15)
				)
			)
		)
		(property "Author" "Antmicro"
			(at 0 0 180)
			(unlocked yes)
			(layer "F.Fab")
			(hide yes)
			(effects
				(font
					(size 1 1)
					(thickness 0.15)
				)
			)
		)
		(property "Val" "20k"
			(at 0 0 180)
			(unlocked yes)
			(layer "F.Fab")
			(hide yes)
			(effects
				(font
					(size 1 1)
					(thickness 0.15)
				)
			)
		)
		(property "Tolerance" "1%"
			(at 0 0 180)
			(unlocked yes)
			(layer "F.Fab")
			(hide yes)
			(effects
				(font
					(size 1 1)
					(thickness 0.15)
				)
			)
		)
		(sheetname "/Power input/")
		(sheetfile "power_input.kicad_sch")
		(attr smd)
		(fp_rect
			(start -0.925 -0.47)
			(end 0.925 0.47)
			(stroke
				(width 0.05)
				(type default)
			)
			(fill no)
			(layer "F.CrtYd")
		)
		(fp_rect
			(start -0.5 -0.25)
			(end 0.5 0.25)
			(stroke
				(width 0.15)
				(type solid)
			)
			(fill no)
			(layer "F.Fab")
		)
		(fp_text user "Author: Antmicro"
			(at -0.95 4.169 180)
			(layer "F.Fab")
			(effects
				(font
					(size 0.7 0.7)
					(thickness 0.15)
				)
				(justify left bottom)
			)
		)
		(fp_text user "${REFERENCE}"
			(at -0.95 3.168 180)
			(layer "F.Fab")
			(effects
				(font
					(size 0.7 0.7)
					(thickness 0.15)
				)
				(justify left bottom)
			)
		)
		(fp_text user "License: Apache-2.0"
			(at -0.95 5.169 180)
			(layer "F.Fab")
			(effects
				(font
					(size 0.7 0.7)
					(thickness 0.15)
				)
				(justify left bottom)
			)
		)
		(pad "1" smd roundrect
			(at -0.48 0 180)
			(size 0.59 0.64)
			(layers "F.Cu" "F.Mask" "F.Paste")
			(roundrect_rratio 0.25)
			(net 344 "/Power input/5V_EN")
			(pintype "passive")
		)
		(pad "2" smd roundrect
			(at 0.48 0 180)
			(size 0.59 0.64)
			(layers "F.Cu" "F.Mask" "F.Paste")
			(roundrect_rratio 0.25)
			(net 412 "Net-(D15-C)")
			(pintype "passive")
		)
	)
)
